# T6G (Grand Teton) — schematic netlist excerpt (pin names and nets, part order shuffled) for the footprints in the layout excerpt that follows; sources: Cadence DE-HDL packaged netlist, KiCad conversion of 04192023_DAF0TMB3IC0_F0TG_MB_C_brd_V02_OCP.brd

Q123  MOSFET_NCH_DUAL  PJT138K IC  pkg SOT363XD  page 134
  S1  = GND
  G1  = P12V_OCP_EN_1_R
  D2  = P12V_OCP_UV_1_R
  S2  = GND
  G2  = P12V_OCP_1_EN_G
  D1  = P12V_OCP_1_EN_G

C715  Q_CAP_DIFFBUS  DIFF BUS_0.22UF 6.3V 20% X6S  pkg C0201  page 66 : \1\ = P5E_CPU1_P1_TX_C_DP<13> ; \2\ = P5E_CPU1_P1_TX_DP<13>
R3135  Q_RES  1K 1% CHIP  pkg 0402LF  page 140 : A = P3V3_AUX ; B = OCP_V3_2_PRSNT1_R_N

(kicad_pcb
	(version 20260206)
	(generator "pcbnew")
	(generator_version "10.0")
	(general
		(thickness 1.6)
		(legacy_teardrops no)
	)
	(paper "A4")
	(title_block
		(title "04192023_DAF0TMB3IC0_F0TG_MB_C_brd_V02_OCP.brd")
		(comment 1 "Grand Teton / footprints 524-526 of 8354")
	)
	(layers
		(0 "F.Cu" signal "TOP")
		(4 "In1.Cu" signal "GND")
		(6 "In2.Cu" signal "IN1")
		(8 "In3.Cu" signal "GND1")
		(10 "In4.Cu" signal "IN2")
		(12 "In5.Cu" signal "GND2")
		(14 "In6.Cu" signal "IN3")
		(16 "In7.Cu" signal "GND3")
		(18 "In8.Cu" signal "VCC")
		(20 "In9.Cu" signal "VCC1")
		(22 "In10.Cu" signal "GND4")
		(24 "In11.Cu" signal "IN4")
		(26 "In12.Cu" signal "GND5")
		(28 "In13.Cu" signal "IN5")
		(30 "In14.Cu" signal "GND6")
		(32 "In15.Cu" signal "IN6")
		(34 "In16.Cu" signal "GND7")
		(2 "B.Cu" signal "BOTTOM")
		(9 "F.Adhes" user "F.Adhesive")
		(11 "B.Adhes" user "B.Adhesive")
		(13 "F.Paste" user "Package Geometry/Pastemask Top")
		(15 "B.Paste" user "Package Geometry/Pastemask Bottom")
		(5 "F.SilkS" user "Ref Des/Silkscreen Top")
		(7 "B.SilkS" user "Ref Des/Silkscreen Bottom")
		(1 "F.Mask" user "Board Geometry/Soldermask Top")
		(3 "B.Mask" user "Board Geometry/Soldermask Bottom")
		(17 "Dwgs.User" user "User.Drawings")
		(19 "Cmts.User" user "User.Comments")
		(21 "Eco1.User" user "User.Eco1")
		(23 "Eco2.User" user "User.Eco2")
		(25 "Edge.Cuts" user "Board Geometry/Outline")
		(27 "Margin" user)
		(31 "F.CrtYd" user "Package Geometry/Place Bound Top")
		(29 "B.CrtYd" user "Package Geometry/Place Bound Bottom")
		(35 "F.Fab" user "Ref Des/Assembly Top")
		(33 "B.Fab" user "Ref Des/Assembly Bottom")
	)
	(footprint ""
		(layer "F.Cu")
		(at 101.044502 -370.57203 -90)
		(property "Reference" "C715"
			(at 0 0 270)
			(layer "F.SilkS")
			(hide yes)
			(effects
				(font
					(size 1.27 1.27)
				)
			)
		)
		(property "Value" ""
			(at 0 0 270)
			(layer "F.Fab")
			(effects
				(font
					(size 1.27 1.27)
				)
			)
		)
		(duplicate_pad_numbers_are_jumpers no)
		(fp_line
			(start -0.299974 0.150114)
			(end -0.299974 -0.150114)
			(stroke
				(width 0.1)
				(type default)
			)
			(layer "F.Fab")
		)
		(fp_line
			(start 0.299974 0.150114)
			(end -0.299974 0.150114)
			(stroke
				(width 0.1)
				(type default)
			)
			(layer "F.Fab")
		)
		(fp_line
			(start -0.299974 -0.150114)
			(end 0.299974 -0.150114)
			(stroke
				(width 0.1)
				(type default)
			)
			(layer "F.Fab")
		)
		(fp_line
			(start 0.299974 -0.150114)
			(end 0.299974 0.150114)
			(stroke
				(width 0.1)
				(type default)
			)
			(layer "F.Fab")
		)
		(pad "1" smd rect
			(at -0.2667 0 270)
			(size 0.3048 0.381)
			(layers "F.Cu" "F.Mask" "F.Paste")
			(net "P5E_CPU1_P1_TX_C_DP<13>")
		)
		(pad "2" smd rect
			(at 0.2667 0 270)
			(size 0.3048 0.381)
			(layers "F.Cu" "F.Mask" "F.Paste")
			(net "P5E_CPU1_P1_TX_DP<13>")
		)
	)
	(footprint ""
		(layer "F.Cu")
		(at 465.169504 -41.105836 180)
		(property "Reference" "Q123"
			(at 1.585214 2.068068 0)
			(unlocked yes)
			(layer "F.SilkS")
			(effects
				(font
					(size 0.7874 0.5842)
					(thickness 0.1524)
				)
				(justify left)
			)
		)
		(property "Value" ""
			(at 0 0 180)
			(layer "F.Fab")
			(effects
				(font
					(size 1.27 1.27)
				)
			)
		)
		(duplicate_pad_numbers_are_jumpers no)
		(fp_line
			(start 1.332738 1.100074)
			(end -1.332738 1.100074)
			(stroke
				(width 0.1524)
				(type default)
			)
			(layer "F.SilkS")
		)
		(fp_line
			(start 1.332738 -1.100074)
			(end 1.332738 1.100074)
			(stroke
				(width 0.1524)
				(type default)
			)
			(layer "F.SilkS")
		)
		(fp_line
			(start 0.4826 -1.100074)
			(end 1.332738 -1.100074)
			(stroke
				(width 0.1524)
				(type default)
			)
			(layer "F.SilkS")
		)
		(fp_line
			(start 0 -0.541274)
			(end 0.4826 -1.100074)
			(stroke
				(width 0.1524)
				(type default)
			)
			(layer "F.SilkS")
		)
		(fp_line
			(start -0.4826 -1.100074)
			(end 0 -0.541274)
			(stroke
				(width 0.1524)
				(type default)
			)
			(layer "F.SilkS")
		)
		(fp_line
			(start -1.332738 1.100074)
			(end -1.332738 -1.100074)
			(stroke
				(width 0.1524)
				(type default)
			)
			(layer "F.SilkS")
		)
		(fp_line
			(start -1.332738 -1.100074)
			(end -0.4826 -1.100074)
			(stroke
				(width 0.1524)
				(type default)
			)
			(layer "F.SilkS")
		)
		(fp_poly
			(pts
				(xy -1.489456 -1.189482) (xy -2.23393 -1.43764) (xy -1.737614 -1.933956)
			)
			(stroke
				(width 0)
				(type default)
			)
			(fill yes)
			(layer "F.SilkS")
		)
		(fp_line
			(start 0.674878 1.100074)
			(end -0.674878 1.100074)
			(stroke
				(width 0.1)
				(type default)
			)
			(layer "F.Fab")
		)
		(fp_line
			(start 0.674878 -1.100074)
			(end 0.674878 1.100074)
			(stroke
				(width 0.1)
				(type default)
			)
			(layer "F.Fab")
		)
		(fp_line
			(start -0.674878 1.100074)
			(end -0.674878 -1.100074)
			(stroke
				(width 0.1)
				(type default)
			)
			(layer "F.Fab")
		)
		(fp_line
			(start -0.674878 -1.100074)
			(end 0.674878 -1.100074)
			(stroke
				(width 0.1)
				(type default)
			)
			(layer "F.Fab")
		)
		(fp_poly
			(pts
				(xy -2.2352 -0.298958) (xy -2.2352 -1.001014) (xy -1.533144 -0.649986)
			)
			(stroke
				(width 0)
				(type default)
			)
			(fill yes)
			(layer "F.Fab")
		)
		(pad "1" smd rect
			(at -0.94996 -0.649986 270)
			(size 0.4318 0.508)
			(layers "F.Cu" "F.Mask" "F.Paste")
			(net "GND")
		)
		(pad "2" smd rect
			(at -0.94996 0 270)
			(size 0.4318 0.508)
			(layers "F.Cu" "F.Mask" "F.Paste")
			(net "P12V_OCP_EN_1_R")
		)
		(pad "3" smd rect
			(at -0.94996 0.649986 270)
			(size 0.4318 0.508)
			(layers "F.Cu" "F.Mask" "F.Paste")
			(net "P12V_OCP_UV_1_R")
		)
		(pad "4" smd rect
			(at 0.94996 0.649986 270)
			(size 0.4318 0.508)
			(layers "F.Cu" "F.Mask" "F.Paste")
			(net "GND")
		)
		(pad "5" smd rect
			(at 0.94996 0 270)
			(size 0.4318 0.508)
			(layers "F.Cu" "F.Mask" "F.Paste")
			(net "P12V_OCP_1_EN_G")
		)
		(pad "6" smd rect
			(at 0.94996 -0.649986 270)
			(size 0.4318 0.508)
			(layers "F.Cu" "F.Mask" "F.Paste")
			(net "P12V_OCP_1_EN_G")
		)
	)
	(footprint ""
		(layer "F.Cu")
		(at 9.74471 -78.180692)
		(property "Reference" "R3135"
			(at 0 0 0)
			(layer "F.SilkS")
			(hide yes)
			(effects
				(font
					(size 1.27 1.27)
				)
			)
		)
		(property "Value" ""
			(at 0 0 0)
			(layer "F.Fab")
			(effects
				(font
					(size 1.27 1.27)
				)
			)
		)
		(duplicate_pad_numbers_are_jumpers no)
		(fp_line
			(start -0.7874 -0.4064)
			(end 0.7874 -0.4064)
			(stroke
				(width 0.1524)
				(type default)
			)
			(layer "F.SilkS")
		)
		(fp_line
			(start -0.7874 0.4064)
			(end -0.7874 -0.4064)
			(stroke
				(width 0.1524)
				(type default)
			)
			(layer "F.SilkS")
		)
		(fp_line
			(start 0.7874 -0.4064)
			(end 0.7874 0.4064)
			(stroke
				(width 0.1524)
				(type default)
			)
			(layer "F.SilkS")
		)
		(fp_line
			(start 0.7874 0.4064)
			(end -0.7874 0.4064)
			(stroke
				(width 0.1524)
				(type default)
			)
			(layer "F.SilkS")
		)
		(fp_line
			(start -0.67945 -0.305054)
			(end -0.12065 -0.305054)
			(stroke
				(width 0.1)
				(type default)
			)
			(layer "F.Fab")
		)
		(fp_line
			(start -0.67945 0.3048)
			(end -0.67945 -0.305054)
			(stroke
				(width 0.1)
				(type default)
			)
			(layer "F.Fab")
		)
		(fp_line
			(start -0.12065 -0.305054)
			(end -0.12065 -0.2794)
			(stroke
				(width 0.1)
				(type default)
			)
			(layer "F.Fab")
		)
		(fp_line
			(start -0.12065 -0.2794)
			(end 0.12065 -0.2794)
			(stroke
				(width 0.1)
				(type default)
			)
			(layer "F.Fab")
		)
		(fp_line
			(start -0.12065 0.2794)
			(end -0.12065 0.3048)
			(stroke
				(width 0.1)
				(type default)
			)
			(layer "F.Fab")
		)
		(fp_line
			(start -0.12065 0.3048)
			(end -0.67945 0.3048)
			(stroke
				(width 0.1)
				(type default)
			)
			(layer "F.Fab")
		)
		(fp_line
			(start 0.120396 0.2794)
			(end -0.12065 0.2794)
			(stroke
				(width 0.1)
				(type default)
			)
			(layer "F.Fab")
		)
		(fp_line
			(start 0.120396 0.3048)
			(end 0.120396 0.2794)
			(stroke
				(width 0.1)
				(type default)
			)
			(layer "F.Fab")
		)
		(fp_line
			(start 0.12065 -0.3048)
			(end 0.67945 -0.3048)
			(stroke
				(width 0.1)
				(type default)
			)
			(layer "F.Fab")
		)
		(fp_line
			(start 0.12065 -0.2794)
			(end 0.12065 -0.3048)
			(stroke
				(width 0.1)
				(type default)
			)
			(layer "F.Fab")
		)
		(fp_line
			(start 0.67945 -0.3048)
			(end 0.67945 0.3048)
			(stroke
				(width 0.1)
				(type default)
			)
			(layer "F.Fab")
		)
		(fp_line
			(start 0.67945 0.3048)
			(end 0.120396 0.3048)
			(stroke
				(width 0.1)
				(type default)
			)
			(layer "F.Fab")
		)
		(pad "1" smd circle
			(at -0.40005 0)
			(size 0 0)
			(layers "F.Cu" "F.Mask" "F.Paste")
			(net "P3V3_AUX")
		)
		(pad "2" smd circle
			(at 0.40005 0)
			(size 0 0)
			(layers "F.Cu" "F.Mask" "F.Paste")
			(net "OCP_V3_2_PRSNT1_R_N")
		)
	)
)
